FILE_TYPE = CONNECTIVITY;
{Allegro Design Entry HDL 16.6-p007 (v16-6-112F) 10/10/2012}
"PAGE_NUMBER" = 49;
0"NC";
1"M_D_DQS_DN<17:0>";
2"M_D_DQS_DP<17:0>";
3"M_D_DQ<63:0>";
4"M_D_BG<1:0>";
5"M_D_BA<1:0>";
6"M_D_MA<17:0>";
7"M_D_CLK_DP<3:0>";
8"M_D_CLK_DN<3:0>";
9"M_D_CKE<3:0>";
10"M_D_CS_N<7:0>";
11"M_D_ECC<7:0>";
12"M_D_ODT<3:0>";
13"PVDDQ_DEF\g";
14"PVTT_DEF\g";
15"GND\g";
16"GND\g"ROOM"TBD"BOM_COST"TBD";
17"GND\g";
18"PVPP_DEF\g";
19"PVPP_DEF\g";
20"P12V_NVDIMM_DEF\g";
21"GND\g";
22"TP_CH_D_DIMM_D0_RFU_0";
23"TP_CH_D_DIMM_D0_RFU_1";
24"TP_CH_D_DIMM_D0_RFU_2";
25"M_D_VREF";
26"SMB_DDR_DEF_VPP_SCL";
27"SMB_DDR_DEF_VPP_SDA";
28"FM_ADR_COMPLETE_DEF_N";
29"M_D_ACT_N";
30"M_D_DQS_DN<7>";
31"M_D_MA<12>";
32"M_D_DQ<6>";
33"M_D_BG<0>";
34"M_D_MA<1>";
35"M_D_MA<4>";
36"M_D_MA<6>";
37"M_D_MA<7>";
38"M_D_MA<8>";
39"M_D_MA<9>";
40"M_D_MA<10>";
41"M_D_MA<11>";
42"M_D_MA<15>";
43"M_D_MA<16>";
44"M_D_DQ<59>";
45"M_D_DQS_DP<12>";
46"FM_DIMM_EVENT_COD_N";
47"M_DEF_RST_N";
48"M_D_PAR";
49"M_D_C<2>";
50"M_D_CS_N<0>";
51"M_D_ODT<1>";
52"M_D_ODT<0>";
53"M_D_ECC<6>";
54"M_D_CKE<1>";
55"M_D_CLK_DN<0>";
56"M_D_ECC<1>";
57"M_D_ECC<0>";
58"M_D_ECC<3>";
59"M_D_ECC<2>";
60"M_D_ECC<5>";
61"M_D_ECC<4>";
62"M_D_ECC<7>";
63"M_D_CS_N<1>";
64"M_D_CS_N<2>";
65"M_D_CS_N<3>";
66"M_D_CKE<0>";
67"M_D_CLK_DP<1>";
68"M_D_CLK_DN<1>";
69"M_D_CLK_DP<0>";
70"M_D_ALERT_N";
71"M_D_DQ<1>";
72"M_D_DQ<4>";
73"M_D_DQ<5>";
74"M_D_DQ<2>";
75"M_D_DQ<3>";
76"M_D_DQ<0>";
77"M_D_DQ<7>";
78"M_D_DQ<9>";
79"M_D_DQ<8>";
80"M_D_DQ<11>";
81"M_D_DQ<10>";
82"M_D_DQ<14>";
83"M_D_DQ<13>";
84"M_D_DQ<12>";
85"M_D_DQ<15>";
86"M_D_DQ<17>";
87"M_D_DQ<16>";
88"M_D_DQ<19>";
89"M_D_DQ<18>";
90"M_D_DQ<21>";
91"M_D_DQ<20>";
92"M_D_DQ<27>";
93"M_D_DQ<23>";
94"M_D_DQ<22>";
95"M_D_DQ<25>";
96"M_D_DQ<24>";
97"M_D_DQ<26>";
98"M_D_DQ<31>";
99"M_D_DQ<30>";
100"M_D_DQ<29>";
101"M_D_DQ<28>";
102"M_D_DQ<37>";
103"M_D_DQ<34>";
104"M_D_DQ<33>";
105"M_D_DQ<32>";
106"M_D_DQ<35>";
107"M_D_DQ<39>";
108"M_D_DQ<36>";
109"M_D_DQ<38>";
110"M_D_DQ<41>";
111"M_D_DQ<40>";
112"M_D_MA<14>";
113"M_D_MA<2>";
114"M_D_BA<0>";
115"M_D_MA<5>";
116"M_D_MA<3>";
117"M_D_MA<17>";
118"M_D_MA<13>";
119"M_D_MA<0>";
120"M_D_BA<1>";
121"M_D_BG<1>";
122"M_D_DQ<46>";
123"M_D_DQ<43>";
124"M_D_DQ<42>";
125"M_D_DQ<45>";
126"M_D_DQ<44>";
127"M_D_DQ<47>";
128"M_D_DQ<49>";
129"M_D_DQ<48>";
130"M_D_DQ<51>";
131"M_D_DQ<50>";
132"M_D_DQ<53>";
133"M_D_DQ<52>";
134"M_D_DQ<55>";
135"M_D_DQ<56>";
136"M_D_DQ<54>";
137"M_D_DQ<57>";
138"M_D_DQ<63>";
139"M_D_DQ<60>";
140"M_D_DQ<58>";
141"M_D_DQ<61>";
142"M_D_DQ<62>";
143"M_D_DQS_DN<6>";
144"M_D_DQS_DP<5>";
145"M_D_DQS_DN<5>";
146"M_D_DQS_DP<4>";
147"M_D_DQS_DN<4>";
148"M_D_DQS_DP<3>";
149"M_D_DQS_DN<3>";
150"M_D_DQS_DP<2>";
151"M_D_DQS_DN<2>";
152"M_D_DQS_DP<1>";
153"M_D_DQS_DN<1>";
154"M_D_DQS_DP<0>";
155"M_D_DQS_DN<0>";
156"M_D_DQS_DP<9>";
157"M_D_DQS_DN<9>";
158"M_D_DQS_DP<8>";
159"M_D_DQS_DN<8>";
160"M_D_DQS_DP<7>";
161"M_D_DQS_DP<6>";
162"M_D_DQS_DP<16>";
163"M_D_DQS_DN<16>";
164"M_D_DQS_DP<15>";
165"M_D_DQS_DN<15>";
166"M_D_DQS_DP<14>";
167"M_D_DQS_DN<14>";
168"M_D_DQS_DP<13>";
169"M_D_DQS_DN<13>";
170"M_D_DQS_DN<12>";
171"M_D_DQS_DP<11>";
172"M_D_DQS_DN<11>";
173"M_D_DQS_DP<10>";
174"M_D_DQS_DN<10>";
175"M_D_DQS_DP<17>";
176"M_D_DQS_DN<17>";
%"TAP"
"6","(650,5100)","2","mstr_standard","I10";
;
CDS_LIB"mstr_standard"
BODY_TYPE"PLUMBING"
HDL_TAP"TRUE";
"B \NAC \NWC"2;
"S \NAC"
BN"16"162;
%"TAP"
"6","(-1750,2500)","2","mstr_standard","I100";
;
CDS_LIB"mstr_standard"
BODY_TYPE"PLUMBING"
HDL_TAP"TRUE";
"B \NAC \NWC"3;
"S \NAC"
BN"11"80;
%"TAP"
"6","(-1750,2450)","2","mstr_standard","I101";
;
CDS_LIB"mstr_standard"
BODY_TYPE"PLUMBING"
HDL_TAP"TRUE";
"B \NAC \NWC"3;
"S \NAC"
BN"8"79;
%"TAP"
"6","(-1750,2350)","2","mstr_standard","I102";
;
CDS_LIB"mstr_standard"
BODY_TYPE"PLUMBING"
HDL_TAP"TRUE";
"B \NAC \NWC"3;
"S \NAC"
BN"6"32;
%"TAP"
"6","(-1750,2400)","2","mstr_standard","I103";
;
CDS_LIB"mstr_standard"
BODY_TYPE"PLUMBING"
HDL_TAP"TRUE";
"B \NAC \NWC"3;
"S \NAC"
BN"9"78;
%"TAP"
"6","(-1750,2300)","2","mstr_standard","I104";
;
CDS_LIB"mstr_standard"
BODY_TYPE"PLUMBING"
HDL_TAP"TRUE";
"B \NAC \NWC"3;
"S \NAC"
BN"7"77;
%"TAP"
"6","(-1750,2250)","2","mstr_standard","I105";
;
CDS_LIB"mstr_standard"
BODY_TYPE"PLUMBING"
HDL_TAP"TRUE";
"B \NAC \NWC"3;
"S \NAC"
BN"4"72;
%"TAP"
"6","(-1750,2150)","2","mstr_standard","I106";
;
CDS_LIB"mstr_standard"
BODY_TYPE"PLUMBING"
HDL_TAP"TRUE";
"B \NAC \NWC"3;
"S \NAC"
BN"2"74;
%"TAP"
"6","(-1750,2200)","2","mstr_standard","I107";
;
CDS_LIB"mstr_standard"
BODY_TYPE"PLUMBING"
HDL_TAP"TRUE";
"B \NAC \NWC"3;
"S \NAC"
BN"5"73;
%"TAP"
"6","(-1750,2050)","2","mstr_standard","I108";
;
CDS_LIB"mstr_standard"
BODY_TYPE"PLUMBING"
HDL_TAP"TRUE";
"B \NAC \NWC"3;
"S \NAC"
BN"0"76;
%"TAP"
"6","(-1750,2100)","2","mstr_standard","I109";
;
CDS_LIB"mstr_standard"
BODY_TYPE"PLUMBING"
HDL_TAP"TRUE";
"B \NAC \NWC"3;
"S \NAC"
BN"3"75;
%"TAP"
"6","(650,5000)","2","mstr_standard","I11";
;
CDS_LIB"mstr_standard"
BODY_TYPE"PLUMBING"
HDL_TAP"TRUE";
"B \NAC \NWC"2;
"S \NAC"
BN"15"164;
%"TAP"
"6","(-1750,2000)","2","mstr_standard","I110";
;
CDS_LIB"mstr_standard"
BODY_TYPE"PLUMBING"
HDL_TAP"TRUE";
"B \NAC \NWC"3;
"S \NAC"
BN"1"71;
%"SCONN288_H44441004"
"1","(-2500,3500)","0","mstr_sconn","I111";
;
CDS_SEC"1"
LOCATION"J4B1"
MATERIAL"SCONN"
PART_NUMBER"H44441-004"
PACK_TYPE"PIP"
BOM_COST"MEM"
CDS_LIB"mstr_sconn"
SEC_TYPE"PIP"
SEC"1"
CDS_LOCATION"J4B1"
ROOM"DDR4_CH_D";
"DQ<63>"
$PN"280"142;
"DQ<62>"
$PN"135"138;
"DQ<61>"
$PN"273"139;
"DQ<5>"
$PN"148"72;
"DQ<4>"
$PN"3"73;
"DQ<3>"
$PN"157"74;
"DQ<2>"
$PN"12"75;
"DQ<47>"
$PN"258"122;
"DQ<48>"
$PN"119"128;
"DQ<49>"
$PN"264"129;
"DQ<50>"
$PN"126"130;
"DQ<51>"
$PN"271"131;
"DQ<52>"
$PN"117"132;
"DQ<53>"
$PN"262"133;
"DQ<54>"
$PN"124"134;
"DQ<58>"
$PN"137"44;
"DQ<57>"
$PN"275"135;
"SAVE_N_NC"
$PN"230"28;
"RFU<1>"
$PN"227"23;
"RFU<0>"
$PN"205"22;
"DQ<17>"
$PN"172"87;
"DQ<15>"
$PN"166"82;
"DQ<26>"
$PN"45"92;
"DQ<27>"
$PN"190"97;
"S0_N"
$PN"84"50;
"CKE<0>"
$PN"60"66;
"ODT<1>"
$PN"91"51;
"ODT<0>"
$PN"87"52;
"CB<7>"
$PN"199"53;
"A16_RAS_N"
$PN"82"43;
"A15_CAS_N"
$PN"86"42;
"A14_WE_N"
$PN"228"112;
"A11"
$PN"210"41;
"A10"
$PN"225"40;
"DQ<38>"
$PN"102"107;
"DQ<36>"
$PN"95"102;
"DQ<35>"
$PN"249"103;
"A2"
$PN"216"113;
"ALERT_N"
$PN"208"70;
"ACT_N"
$PN"62"29;
"DQ<0>"
$PN"5"71;
"DQ<1>"
$PN"150"76;
"SA<1>"
$PN"140"16;
"SA<2>"
$PN"238"16;
"VDDSPD"
$PN"284"19;
"SA<0>"
$PN"139"16;
"BA<0>"
$PN"81"114;
"BG<1>"
$PN"207"121;
"BG<0>"
$PN"63"33;
"CK1P"
$PN"218"67;
"VREFCA"
$PN"146"25;
"SDA"
$PN"285"27;
"SCL"
$PN"141"26;
"RFU<2>"
$PN"144"24;
"RESET_N"
$PN"58"47;
"PAR"
$PN"222"48;
"EVENT_N"
$PN"78"46;
"DQ<6>"
$PN"10"77;
"DQ<7>"
$PN"155"32;
"DQ<8>"
$PN"16"78;
"DQ<9>"
$PN"161"79;
"DQ<10>"
$PN"23"80;
"DQ<11>"
$PN"168"81;
"DQ<12>"
$PN"14"83;
"DQ<13>"
$PN"159"84;
"DQ<14>"
$PN"21"85;
"DQ<16>"
$PN"27"86;
"DQ<18>"
$PN"34"88;
"DQ<19>"
$PN"179"89;
"DQ<20>"
$PN"25"90;
"DQ<21>"
$PN"170"91;
"DQ<22>"
$PN"32"93;
"DQ<23>"
$PN"177"94;
"DQ<24>"
$PN"38"95;
"DQ<25>"
$PN"183"96;
"DQ<30>"
$PN"43"98;
"DQ<31>"
$PN"188"99;
"DQ<32>"
$PN"97"104;
"DQ<33>"
$PN"242"105;
"DQ<34>"
$PN"104"106;
"DQ<37>"
$PN"240"108;
"DQ<39>"
$PN"247"109;
"DQ<40>"
$PN"108"110;
"DQ<41>"
$PN"253"111;
"DQ<42>"
$PN"115"123;
"DQ<43>"
$PN"260"124;
"DQ<44>"
$PN"106"125;
"DQ<45>"
$PN"251"126;
"DQ<46>"
$PN"113"127;
"DQ<55>"
$PN"269"136;
"DQ<56>"
$PN"130"137;
"DQ<59>"
$PN"282"140;
"DQ<60>"
$PN"128"141;
"CKE<1>"
$PN"203"54;
"CK0N"
$PN"75"55;
"CB<0>"
$PN"49"56;
"CB<1>"
$PN"194"57;
"CB<2>"
$PN"56"58;
"CB<3>"
$PN"201"59;
"CB<4>"
$PN"47"60;
"CB<5>"
$PN"192"61;
"CB<6>"
$PN"54"62;
"A9"
$PN"66"39;
"A8"
$PN"68"38;
"A7"
$PN"211"37;
"A6"
$PN"69"36;
"A5"
$PN"213"115;
"A4"
$PN"214"35;
"A3"
$PN"71"116;
"A17"
$PN"234"117;
"A13"
$PN"232"118;
"A12"
$PN"65"31;
"A1"
$PN"72"34;
"A0"
$PN"79"119;
"C<2>"
$PN"235"49;
"DQ<28>"
$PN"36"100;
"DQ<29>"
$PN"181"101;
"S1_N"
$PN"89"63;
"S2_N_C<0>"
$PN"93"64;
"S3_N_C<1>"
$PN"237"65;
"CK0P"
$PN"74"69;
"CK1N"
$PN"219"68;
"BA<1>"
$PN"224"120;
%"TAP"
"6","(-3250,5150)","0","mstr_standard","I112";
;
CDS_LIB"mstr_standard"
BODY_TYPE"PLUMBING"
HDL_TAP"TRUE";
"B \NAC \NWC"6;
"S \NAC"
BN"17"117;
%"TAP"
"6","(-3250,5100)","0","mstr_standard","I113";
;
CDS_LIB"mstr_standard"
BODY_TYPE"PLUMBING"
HDL_TAP"TRUE";
"B \NAC \NWC"6;
"S \NAC"
BN"16"43;
%"TAP"
"6","(-3250,5050)","0","mstr_standard","I114";
;
CDS_LIB"mstr_standard"
BODY_TYPE"PLUMBING"
HDL_TAP"TRUE";
"B \NAC \NWC"6;
"S \NAC"
BN"15"42;
%"TAP"
"6","(-3250,5000)","0","mstr_standard","I115";
;
CDS_LIB"mstr_standard"
BODY_TYPE"PLUMBING"
HDL_TAP"TRUE";
"B \NAC \NWC"6;
"S \NAC"
BN"14"112;
%"TAP"
"6","(-3250,4950)","0","mstr_standard","I116";
;
CDS_LIB"mstr_standard"
BODY_TYPE"PLUMBING"
HDL_TAP"TRUE";
"B \NAC \NWC"6;
"S \NAC"
BN"13"118;
%"TAP"
"6","(-3250,4900)","0","mstr_standard","I117";
;
CDS_LIB"mstr_standard"
BODY_TYPE"PLUMBING"
HDL_TAP"TRUE";
"B \NAC \NWC"6;
"S \NAC"
BN"12"31;
%"TAP"
"6","(-3250,4850)","0","mstr_standard","I118";
;
CDS_LIB"mstr_standard"
BODY_TYPE"PLUMBING"
HDL_TAP"TRUE";
"B \NAC \NWC"6;
"S \NAC"
BN"11"41;
%"TAP"
"6","(-3250,4800)","0","mstr_standard","I119";
;
CDS_LIB"mstr_standard"
BODY_TYPE"PLUMBING"
HDL_TAP"TRUE";
"B \NAC \NWC"6;
"S \NAC"
BN"10"40;
%"TAP"
"6","(650,4900)","2","mstr_standard","I12";
;
CDS_LIB"mstr_standard"
BODY_TYPE"PLUMBING"
HDL_TAP"TRUE";
"B \NAC \NWC"2;
"S \NAC"
BN"14"166;
%"TAP"
"6","(-3250,4750)","0","mstr_standard","I120";
;
CDS_LIB"mstr_standard"
BODY_TYPE"PLUMBING"
HDL_TAP"TRUE";
"B \NAC \NWC"6;
"S \NAC"
BN"9"39;
%"TAP"
"6","(-3250,4700)","0","mstr_standard","I121";
;
CDS_LIB"mstr_standard"
BODY_TYPE"PLUMBING"
HDL_TAP"TRUE";
"B \NAC \NWC"6;
"S \NAC"
BN"8"38;
%"TAP"
"6","(-3250,4650)","0","mstr_standard","I122";
;
CDS_LIB"mstr_standard"
BODY_TYPE"PLUMBING"
HDL_TAP"TRUE";
"B \NAC \NWC"6;
"S \NAC"
BN"7"37;
%"TAP"
"6","(-3250,4600)","0","mstr_standard","I123";
;
CDS_LIB"mstr_standard"
BODY_TYPE"PLUMBING"
HDL_TAP"TRUE";
"B \NAC \NWC"6;
"S \NAC"
BN"6"36;
%"TAP"
"6","(-3250,4550)","0","mstr_standard","I124";
;
CDS_LIB"mstr_standard"
BODY_TYPE"PLUMBING"
HDL_TAP"TRUE";
"B \NAC \NWC"6;
"S \NAC"
BN"5"115;
%"TAP"
"6","(-3250,4500)","0","mstr_standard","I125";
;
CDS_LIB"mstr_standard"
BODY_TYPE"PLUMBING"
HDL_TAP"TRUE";
"B \NAC \NWC"6;
"S \NAC"
BN"4"35;
%"TAP"
"6","(-3250,4450)","0","mstr_standard","I126";
;
CDS_LIB"mstr_standard"
BODY_TYPE"PLUMBING"
HDL_TAP"TRUE";
"B \NAC \NWC"6;
"S \NAC"
BN"3"116;
%"TAP"
"6","(-3250,4400)","0","mstr_standard","I127";
;
CDS_LIB"mstr_standard"
BODY_TYPE"PLUMBING"
HDL_TAP"TRUE";
"B \NAC \NWC"6;
"S \NAC"
BN"2"113;
%"TAP"
"6","(-3250,4350)","0","mstr_standard","I128";
;
CDS_LIB"mstr_standard"
BODY_TYPE"PLUMBING"
HDL_TAP"TRUE";
"B \NAC \NWC"6;
"S \NAC"
BN"1"34;
%"TAP"
"6","(-3250,4300)","0","mstr_standard","I129";
;
CDS_LIB"mstr_standard"
BODY_TYPE"PLUMBING"
HDL_TAP"TRUE";
"B \NAC \NWC"6;
"S \NAC"
BN"0"119;
%"TAP"
"6","(650,4800)","2","mstr_standard","I13";
;
CDS_LIB"mstr_standard"
BODY_TYPE"PLUMBING"
HDL_TAP"TRUE";
"B \NAC \NWC"2;
"S \NAC"
BN"13"168;
%"TAP"
"6","(-3250,4200)","0","mstr_standard","I130";
;
CDS_LIB"mstr_standard"
BODY_TYPE"PLUMBING"
HDL_TAP"TRUE";
"B \NAC \NWC"5;
"S \NAC"
BN"1"120;
%"TAP"
"6","(-3250,4150)","0","mstr_standard","I133";
;
CDS_LIB"mstr_standard"
BODY_TYPE"PLUMBING"
HDL_TAP"TRUE";
"B \NAC \NWC"5;
"S \NAC"
BN"0"114;
%"TAP"
"6","(-3250,4100)","0","mstr_standard","I134";
;
CDS_LIB"mstr_standard"
BODY_TYPE"PLUMBING"
HDL_TAP"TRUE";
"B \NAC \NWC"4;
"S \NAC"
BN"1"121;
%"TAP"
"6","(-3250,4050)","0","mstr_standard","I135";
;
CDS_LIB"mstr_standard"
BODY_TYPE"PLUMBING"
HDL_TAP"TRUE";
"B \NAC \NWC"4;
"S \NAC"
BN"0"33;
%"TAP"
"6","(-3250,3050)","0","mstr_standard","I138";
;
CDS_LIB"mstr_standard"
BODY_TYPE"PLUMBING"
HDL_TAP"TRUE";
"B \NAC \NWC"11;
"S \NAC"
BN"7"62;
%"TAP"
"6","(-3250,3100)","0","mstr_standard","I139";
;
CDS_LIB"mstr_standard"
BODY_TYPE"PLUMBING"
HDL_TAP"TRUE";
"B \NAC \NWC"11;
"S \NAC"
BN"6"53;
%"TAP"
"6","(650,4600)","2","mstr_standard","I14";
;
CDS_LIB"mstr_standard"
BODY_TYPE"PLUMBING"
HDL_TAP"TRUE";
"B \NAC \NWC"2;
"S \NAC"
BN"11"171;
%"TAP"
"6","(-3250,3000)","0","mstr_standard","I140";
;
CDS_LIB"mstr_standard"
BODY_TYPE"PLUMBING"
HDL_TAP"TRUE";
"B \NAC \NWC"11;
"S \NAC"
BN"4"61;
%"TAP"
"6","(-3250,2950)","0","mstr_standard","I141";
;
CDS_LIB"mstr_standard"
BODY_TYPE"PLUMBING"
HDL_TAP"TRUE";
"B \NAC \NWC"11;
"S \NAC"
BN"5"60;
%"TAP"
"6","(-3250,2900)","0","mstr_standard","I142";
;
CDS_LIB"mstr_standard"
BODY_TYPE"PLUMBING"
HDL_TAP"TRUE";
"B \NAC \NWC"11;
"S \NAC"
BN"2"59;
%"TAP"
"6","(-3250,2850)","0","mstr_standard","I143";
;
CDS_LIB"mstr_standard"
BODY_TYPE"PLUMBING"
HDL_TAP"TRUE";
"B \NAC \NWC"11;
"S \NAC"
BN"3"58;
%"TAP"
"6","(-3250,2800)","0","mstr_standard","I144";
;
CDS_LIB"mstr_standard"
BODY_TYPE"PLUMBING"
HDL_TAP"TRUE";
"B \NAC \NWC"11;
"S \NAC"
BN"0"57;
%"TAP"
"6","(-3250,2750)","0","mstr_standard","I145";
;
CDS_LIB"mstr_standard"
BODY_TYPE"PLUMBING"
HDL_TAP"TRUE";
"B \NAC \NWC"11;
"S \NAC"
BN"1"56;
%"TAP"
"6","(650,4700)","2","mstr_standard","I15";
;
CDS_LIB"mstr_standard"
BODY_TYPE"PLUMBING"
HDL_TAP"TRUE";
"B \NAC \NWC"2;
"S \NAC"
BN"12"45;
%"TAP"
"6","(-3250,3950)","0","mstr_standard","I152";
;
CDS_LIB"mstr_standard"
BODY_TYPE"PLUMBING"
HDL_TAP"TRUE";
"B \NAC \NWC"7;
"S \NAC"
BN"1"67;
%"TAP"
"6","(-3250,3850)","0","mstr_standard","I153";
;
CDS_LIB"mstr_standard"
BODY_TYPE"PLUMBING"
HDL_TAP"TRUE";
"B \NAC \NWC"7;
"S \NAC"
BN"0"69;
%"TAP"
"6","(-3450,3900)","0","mstr_standard","I154";
;
CDS_LIB"mstr_standard"
BODY_TYPE"PLUMBING"
HDL_TAP"TRUE";
"B \NAC \NWC"8;
"S \NAC"
BN"1"68;
%"TAP"
"6","(-3450,3800)","0","mstr_standard","I155";
;
CDS_LIB"mstr_standard"
BODY_TYPE"PLUMBING"
HDL_TAP"TRUE";
"B \NAC \NWC"8;
"S \NAC"
BN"0"55;
%"TAP"
"6","(-3250,3650)","0","mstr_standard","I158";
;
CDS_LIB"mstr_standard"
BODY_TYPE"PLUMBING"
HDL_TAP"TRUE";
"B \NAC \NWC"10;
"S \NAC"
BN"3"65;
%"TAP"
"6","(-3250,3600)","0","mstr_standard","I159";
;
CDS_LIB"mstr_standard"
BODY_TYPE"PLUMBING"
HDL_TAP"TRUE";
"B \NAC \NWC"10;
"S \NAC"
BN"2"64;
%"PVDDQ_DEF"
"1","(-1225,2475)","0","mstr_symbols","I16";
;
VOLTAGE"1.2V"
BOM_COST"MEM"
CDS_LIB"mstr_symbols"
BODY_TYPE"PLUMBING"
ROOM"DDR4_CH_B"
HDL_POWER"PVDDQ_DEF";
"G\NAC"13;
%"TAP"
"6","(-3250,3550)","0","mstr_standard","I160";
;
CDS_LIB"mstr_standard"
BODY_TYPE"PLUMBING"
HDL_TAP"TRUE";
"B \NAC \NWC"10;
"S \NAC"
BN"1"63;
%"TAP"
"6","(-3250,3500)","0","mstr_standard","I161";
;
CDS_LIB"mstr_standard"
BODY_TYPE"PLUMBING"
HDL_TAP"TRUE";
"B \NAC \NWC"10;
"S \NAC"
BN"0"50;
%"TAP"
"6","(-3250,3400)","0","mstr_standard","I162";
;
CDS_LIB"mstr_standard"
BODY_TYPE"PLUMBING"
HDL_TAP"TRUE";
"B \NAC \NWC"9;
"S \NAC"
BN"1"54;
%"TAP"
"6","(-3250,3350)","0","mstr_standard","I163";
;
CDS_LIB"mstr_standard"
BODY_TYPE"PLUMBING"
HDL_TAP"TRUE";
"B \NAC \NWC"9;
"S \NAC"
BN"0"66;
%"TAP"
"6","(-3250,3250)","0","mstr_standard","I167";
;
CDS_LIB"mstr_standard"
BODY_TYPE"PLUMBING"
HDL_TAP"TRUE";
"B \NAC \NWC"12;
"S \NAC"
BN"1"51;
%"TAP"
"6","(-3250,3200)","0","mstr_standard","I168";
;
CDS_LIB"mstr_standard"
BODY_TYPE"PLUMBING"
HDL_TAP"TRUE";
"B \NAC \NWC"12;
"S \NAC"
BN"0"52;
%"SCONN288_H44441004"
"4","(-50,1950)","0","mstr_sconn","I169";
;
CDS_SEC"4"
LOCATION"J4B1"
PART_NUMBER"H44441-004"
MATERIAL"SCONN"
PACK_TYPE"PIP"
BOM_COST"MEM"
CDS_LIB"mstr_sconn"
SEC_TYPE"PIP"
SEC"4"
CDS_LOCATION"J4B1"
ROOM"DDR4_CH_D";
"VPP<4>"
$PN"142"18;
"VTT<1>"
$PN"77"14;
"VPP<0>"
$PN"287"18;
"VPP<1>"
$PN"286"18;
"VPP<2>"
$PN"288"18;
"VPP<3>"
$PN"143"18;
"VDD<1>"
$PN"233"13;
"VDD<2>"
$PN"231"13;
"VDD<3>"
$PN"229"13;
"VDD<4>"
$PN"226"13;
"VDD<5>"
$PN"223"13;
"VDD<7>"
$PN"217"13;
"VDD<8>"
$PN"215"13;
"VDD<9>"
$PN"212"13;
"VDD<11>"
$PN"206"13;
"VDD<12>"
$PN"204"13;
"VDD<14>"
$PN"90"13;
"VDD<15>"
$PN"88"13;
"VDD<17>"
$PN"83"13;
"VDD<18>"
$PN"80"13;
"VDD<20>"
$PN"73"13;
"VDD<21>"
$PN"70"13;
"VDD<22>"
$PN"67"13;
"VDD<24>"
$PN"61"13;
"12V<0>"
$PN"145"20;
"12V<1>"
$PN"1"20;
"VTT<0>"
$PN"221"14;
"VDD<25>"
$PN"59"13;
"VDD<23>"
$PN"64"13;
"VDD<19>"
$PN"76"13;
"VDD<16>"
$PN"85"13;
"VDD<13>"
$PN"92"13;
"VDD<10>"
$PN"209"13;
"VDD<6>"
$PN"220"13;
"VDD<0>"
$PN"236"13;
%"PVTT_DEF"
"1","(-925,2650)","0","mstr_symbols","I170";
;
VOLTAGE"0.6V"
BOM_COST"MEM"
CDS_LIB"mstr_symbols"
BODY_TYPE"PLUMBING"
ROOM"DDR4_CH_B"
HDL_POWER"PVTT_DEF";
"G\NAC"14;
%"GND"
"1","(2500,1150)","2","mstr_symbols","I171";
;
VOLTAGE"0"
SIZE"1B"
CDS_LIB"mstr_symbols"
BOM_COST"MEM"
BODY_TYPE"PLUMBING"
ROOM"DDR4_CH_B"
HDL_POWER"GND";
"A\NAC"15;
%"GND"
"1","(-5100,2100)","2","mstr_symbols","I178";
;
VOLTAGE"0"
CDS_LIB"mstr_symbols"
SIZE"1B"
BOM_COST"MEM"
BODY_TYPE"PLUMBING"
ROOM"DDR4_CH_B"
HDL_POWER"GND";
"A\NAC"16;
%"CAP_A"
"1","(-4650,1800)","2","dev_discrete","I179";
;
CDS_SEC"1"
LOCATION"C4B12"
PART_NUMBER"A36096-045"
VALUE"0.01UF"
TOLERANCE"10%"
VOLTAGE"25V"
MATERIAL"X7R"
PACK_TYPE"0402V"
CDS_LOCATION"C4B12"
BOM_COST"MEM"
CDS_LIB"dev_discrete"
ROOM"DDR4_CH_B"
SEC"1"
SEC_TYPE"0402V";
"B"
$PN"2"17;
"A"
$PN"1"25;
%"GND"
"1","(-4650,1550)","0","mstr_symbols","I180";
;
VOLTAGE"0"
SIZE"1B"
CDS_LIB"mstr_symbols"
BOM_COST"MEM"
BODY_TYPE"PLUMBING"
ROOM"DDR4_CH_B"
HDL_POWER"GND";
"A\NAC"17;
%"PVPP_DEF"
"1","(-750,2950)","0","mstr_symbols","I181";
;
VOLTAGE"2.5V"
BOM_COST"MEM"
CDS_LIB"mstr_symbols"
BODY_TYPE"PLUMBING"
ROOM"DDR4_CH_B"
HDL_POWER"PVPP_DEF";
"G\NAC"18;
%"PVPP_DEF"
"1","(-5100,2500)","0","mstr_symbols","I182";
;
VOLTAGE"2.5V"
BOM_COST"MEM"
CDS_LIB"mstr_symbols"
BODY_TYPE"PLUMBING"
ROOM"DDR4_CH_B"
HDL_POWER"PVPP_DEF";
"G\NAC"19;
%"P12V_NVDIMM_DEF"
"1","(650,3025)","0","mstr_symbols","I184";
;
VOLTAGE"12.0"
CDS_LIB"mstr_symbols"
BODY_TYPE"PLUMBING"
HDL_POWER"P12V_NVDIMM_DEF";
"G\NAC"20;
%"TAP"
"6","(900,4550)","2","mstr_standard","I19";
;
CDS_LIB"mstr_standard"
BODY_TYPE"PLUMBING"
HDL_TAP"TRUE";
"B \NAC \NWC"1;
"S \NAC"
BN"11"172;
%"TAP"
"6","(900,4450)","2","mstr_standard","I20";
;
CDS_LIB"mstr_standard"
BODY_TYPE"PLUMBING"
HDL_TAP"TRUE";
"B \NAC \NWC"1;
"S \NAC"
BN"10"174;
%"TAP"
"6","(900,4350)","2","mstr_standard","I21";
;
CDS_LIB"mstr_standard"
BODY_TYPE"PLUMBING"
HDL_TAP"TRUE";
"B \NAC \NWC"1;
"S \NAC"
BN"9"157;
%"TAP"
"6","(900,4250)","2","mstr_standard","I22";
;
CDS_LIB"mstr_standard"
BODY_TYPE"PLUMBING"
HDL_TAP"TRUE";
"B \NAC \NWC"1;
"S \NAC"
BN"8"159;
%"TAP"
"6","(900,4150)","2","mstr_standard","I23";
;
CDS_LIB"mstr_standard"
BODY_TYPE"PLUMBING"
HDL_TAP"TRUE";
"B \NAC \NWC"1;
"S \NAC"
BN"7"30;
%"TAP"
"6","(650,4400)","2","mstr_standard","I24";
;
CDS_LIB"mstr_standard"
BODY_TYPE"PLUMBING"
HDL_TAP"TRUE";
"B \NAC \NWC"2;
"S \NAC"
BN"9"156;
%"TAP"
"6","(650,4500)","2","mstr_standard","I25";
;
CDS_LIB"mstr_standard"
BODY_TYPE"PLUMBING"
HDL_TAP"TRUE";
"B \NAC \NWC"2;
"S \NAC"
BN"10"173;
%"TAP"
"6","(650,4300)","2","mstr_standard","I26";
;
CDS_LIB"mstr_standard"
BODY_TYPE"PLUMBING"
HDL_TAP"TRUE";
"B \NAC \NWC"2;
"S \NAC"
BN"8"158;
%"TAP"
"6","(650,4100)","2","mstr_standard","I27";
;
CDS_LIB"mstr_standard"
BODY_TYPE"PLUMBING"
HDL_TAP"TRUE";
"B \NAC \NWC"2;
"S \NAC"
BN"6"161;
%"TAP"
"6","(650,4200)","2","mstr_standard","I28";
;
CDS_LIB"mstr_standard"
BODY_TYPE"PLUMBING"
HDL_TAP"TRUE";
"B \NAC \NWC"2;
"S \NAC"
BN"7"160;
%"TAP"
"6","(900,4050)","2","mstr_standard","I29";
;
CDS_LIB"mstr_standard"
BODY_TYPE"PLUMBING"
HDL_TAP"TRUE";
"B \NAC \NWC"1;
"S \NAC"
BN"6"143;
%"TAP"
"6","(900,5150)","2","mstr_standard","I3";
;
CDS_LIB"mstr_standard"
BODY_TYPE"PLUMBING"
HDL_TAP"TRUE";
"B \NAC \NWC"1;
"S \NAC"
BN"17"176;
%"TAP"
"6","(900,3950)","2","mstr_standard","I30";
;
CDS_LIB"mstr_standard"
BODY_TYPE"PLUMBING"
HDL_TAP"TRUE";
"B \NAC \NWC"1;
"S \NAC"
BN"5"145;
%"TAP"
"6","(900,3850)","2","mstr_standard","I31";
;
CDS_LIB"mstr_standard"
BODY_TYPE"PLUMBING"
HDL_TAP"TRUE";
"B \NAC \NWC"1;
"S \NAC"
BN"4"147;
%"TAP"
"6","(900,3750)","2","mstr_standard","I32";
;
CDS_LIB"mstr_standard"
BODY_TYPE"PLUMBING"
HDL_TAP"TRUE";
"B \NAC \NWC"1;
"S \NAC"
BN"3"149;
%"TAP"
"6","(900,3650)","2","mstr_standard","I33";
;
CDS_LIB"mstr_standard"
BODY_TYPE"PLUMBING"
HDL_TAP"TRUE";
"B \NAC \NWC"1;
"S \NAC"
BN"2"151;
%"TAP"
"6","(650,3900)","2","mstr_standard","I34";
;
CDS_LIB"mstr_standard"
BODY_TYPE"PLUMBING"
HDL_TAP"TRUE";
"B \NAC \NWC"2;
"S \NAC"
BN"4"146;
%"TAP"
"6","(650,4000)","2","mstr_standard","I35";
;
CDS_LIB"mstr_standard"
BODY_TYPE"PLUMBING"
HDL_TAP"TRUE";
"B \NAC \NWC"2;
"S \NAC"
BN"5"144;
%"TAP"
"6","(650,3800)","2","mstr_standard","I36";
;
CDS_LIB"mstr_standard"
BODY_TYPE"PLUMBING"
HDL_TAP"TRUE";
"B \NAC \NWC"2;
"S \NAC"
BN"3"148;
%"TAP"
"6","(650,3700)","2","mstr_standard","I37";
;
CDS_LIB"mstr_standard"
BODY_TYPE"PLUMBING"
HDL_TAP"TRUE";
"B \NAC \NWC"2;
"S \NAC"
BN"2"150;
%"TAP"
"6","(650,3600)","2","mstr_standard","I38";
;
CDS_LIB"mstr_standard"
BODY_TYPE"PLUMBING"
HDL_TAP"TRUE";
"B \NAC \NWC"2;
"S \NAC"
BN"1"152;
%"TAP"
"6","(900,3450)","2","mstr_standard","I39";
;
CDS_LIB"mstr_standard"
BODY_TYPE"PLUMBING"
HDL_TAP"TRUE";
"B \NAC \NWC"1;
"S \NAC"
BN"0"155;
%"TAP"
"6","(650,5200)","2","mstr_standard","I4";
;
CDS_LIB"mstr_standard"
BODY_TYPE"PLUMBING"
HDL_TAP"TRUE";
"B \NAC \NWC"2;
"S \NAC"
BN"17"175;
%"TAP"
"6","(900,3550)","2","mstr_standard","I40";
;
CDS_LIB"mstr_standard"
BODY_TYPE"PLUMBING"
HDL_TAP"TRUE";
"B \NAC \NWC"1;
"S \NAC"
BN"1"153;
%"TAP"
"6","(650,3500)","2","mstr_standard","I41";
;
CDS_LIB"mstr_standard"
BODY_TYPE"PLUMBING"
HDL_TAP"TRUE";
"B \NAC \NWC"2;
"S \NAC"
BN"0"154;
%"SCONN288_H44441004"
"3","(1800,2450)","0","mstr_sconn","I43";
;
CDS_SEC"3"
PART_NUMBER"H44441-004"
MATERIAL"SCONN"
LOCATION"J4B1"
PACK_TYPE"PIP"
BOM_COST"MEM"
CDS_LIB"mstr_sconn"
SEC_TYPE"PIP"
SEC"3"
CDS_LOCATION"J4B1"
ROOM"DDR4_CH_D";
"VSS<93>"
$PN"2"21;
"VSS<92>"
$PN"4"21;
"VSS<91>"
$PN"6"21;
"VSS<90>"
$PN"9"21;
"VSS<89>"
$PN"11"21;
"VSS<88>"
$PN"13"21;
"VSS<0>"
$PN"283"15;
"VSS<1>"
$PN"281"15;
"VSS<2>"
$PN"279"15;
"VSS<3>"
$PN"276"15;
"VSS<4>"
$PN"274"15;
"VSS<5>"
$PN"272"15;
"VSS<6>"
$PN"270"15;
"VSS<7>"
$PN"268"15;
"VSS<8>"
$PN"265"15;
"VSS<9>"
$PN"263"15;
"VSS<10>"
$PN"261"15;
"VSS<11>"
$PN"259"15;
"VSS<12>"
$PN"257"15;
"VSS<13>"
$PN"254"15;
"VSS<14>"
$PN"252"15;
"VSS<15>"
$PN"250"15;
"VSS<16>"
$PN"248"15;
"VSS<17>"
$PN"246"15;
"VSS<18>"
$PN"243"15;
"VSS<19>"
$PN"241"15;
"VSS<20>"
$PN"239"15;
"VSS<21>"
$PN"202"15;
"VSS<22>"
$PN"200"15;
"VSS<23>"
$PN"198"15;
"VSS<24>"
$PN"195"15;
"VSS<25>"
$PN"193"15;
"VSS<26>"
$PN"191"15;
"VSS<27>"
$PN"189"15;
"VSS<28>"
$PN"187"15;
"VSS<29>"
$PN"184"15;
"VSS<30>"
$PN"182"15;
"VSS<31>"
$PN"180"15;
"VSS<32>"
$PN"178"15;
"VSS<33>"
$PN"176"15;
"VSS<34>"
$PN"173"15;
"VSS<35>"
$PN"171"15;
"VSS<36>"
$PN"169"15;
"VSS<37>"
$PN"167"15;
"VSS<38>"
$PN"165"15;
"VSS<39>"
$PN"162"15;
"VSS<40>"
$PN"160"15;
"VSS<41>"
$PN"158"15;
"VSS<42>"
$PN"156"15;
"VSS<43>"
$PN"154"15;
"VSS<44>"
$PN"151"15;
"VSS<47>"
$PN"138"21;
"VSS<48>"
$PN"136"21;
"VSS<49>"
$PN"134"21;
"VSS<50>"
$PN"131"21;
"VSS<51>"
$PN"129"21;
"VSS<52>"
$PN"127"21;
"VSS<53>"
$PN"125"21;
"VSS<54>"
$PN"123"21;
"VSS<55>"
$PN"120"21;
"VSS<56>"
$PN"118"21;
"VSS<57>"
$PN"116"21;
"VSS<58>"
$PN"114"21;
"VSS<59>"
$PN"112"21;
"VSS<60>"
$PN"109"21;
"VSS<61>"
$PN"107"21;
"VSS<62>"
$PN"105"21;
"VSS<63>"
$PN"103"21;
"VSS<64>"
$PN"101"21;
"VSS<65>"
$PN"98"21;
"VSS<66>"
$PN"96"21;
"VSS<67>"
$PN"94"21;
"VSS<68>"
$PN"57"21;
"VSS<69>"
$PN"55"21;
"VSS<70>"
$PN"53"21;
"VSS<71>"
$PN"50"21;
"VSS<72>"
$PN"48"21;
"VSS<73>"
$PN"46"21;
"VSS<74>"
$PN"44"21;
"VSS<75>"
$PN"42"21;
"VSS<76>"
$PN"39"21;
"VSS<77>"
$PN"37"21;
"VSS<78>"
$PN"35"21;
"VSS<79>"
$PN"33"21;
"VSS<80>"
$PN"31"21;
"VSS<81>"
$PN"28"21;
"VSS<82>"
$PN"26"21;
"VSS<83>"
$PN"24"21;
"VSS<84>"
$PN"22"21;
"VSS<85>"
$PN"20"21;
"VSS<86>"
$PN"17"21;
"VSS<87>"
$PN"15"21;
"VSS<45>"
$PN"149"15;
"VSS<46>"
$PN"147"15;
%"GND"
"1","(1100,1150)","2","mstr_symbols","I44";
;
VOLTAGE"0"
SIZE"1B"
CDS_LIB"mstr_symbols"
BOM_COST"MEM"
BODY_TYPE"PLUMBING"
ROOM"DDR4_CH_B"
HDL_POWER"GND";
"A\NAC"21;
%"TAP"
"6","(-1750,5150)","2","mstr_standard","I46";
;
CDS_LIB"mstr_standard"
BODY_TYPE"PLUMBING"
HDL_TAP"TRUE";
"B \NAC \NWC"3;
"S \NAC"
BN"62"142;
%"TAP"
"6","(-1750,5100)","2","mstr_standard","I47";
;
CDS_LIB"mstr_standard"
BODY_TYPE"PLUMBING"
HDL_TAP"TRUE";
"B \NAC \NWC"3;
"S \NAC"
BN"63"138;
%"TAP"
"6","(-1750,5000)","2","mstr_standard","I48";
;
CDS_LIB"mstr_standard"
BODY_TYPE"PLUMBING"
HDL_TAP"TRUE";
"B \NAC \NWC"3;
"S \NAC"
BN"61"141;
%"TAP"
"6","(-1750,5050)","2","mstr_standard","I49";
;
CDS_LIB"mstr_standard"
BODY_TYPE"PLUMBING"
HDL_TAP"TRUE";
"B \NAC \NWC"3;
"S \NAC"
BN"60"139;
%"TAP"
"6","(900,5050)","2","mstr_standard","I5";
;
CDS_LIB"mstr_standard"
BODY_TYPE"PLUMBING"
HDL_TAP"TRUE";
"B \NAC \NWC"1;
"S \NAC"
BN"16"163;
%"TAP"
"6","(-1750,4950)","2","mstr_standard","I50";
;
CDS_LIB"mstr_standard"
BODY_TYPE"PLUMBING"
HDL_TAP"TRUE";
"B \NAC \NWC"3;
"S \NAC"
BN"58"140;
%"TAP"
"6","(-1750,4850)","2","mstr_standard","I51";
;
CDS_LIB"mstr_standard"
BODY_TYPE"PLUMBING"
HDL_TAP"TRUE";
"B \NAC \NWC"3;
"S \NAC"
BN"56"135;
%"TAP"
"6","(-1750,4900)","2","mstr_standard","I52";
;
CDS_LIB"mstr_standard"
BODY_TYPE"PLUMBING"
HDL_TAP"TRUE";
"B \NAC \NWC"3;
"S \NAC"
BN"59"44;
%"TAP"
"6","(-1750,4800)","2","mstr_standard","I53";
;
CDS_LIB"mstr_standard"
BODY_TYPE"PLUMBING"
HDL_TAP"TRUE";
"B \NAC \NWC"3;
"S \NAC"
BN"57"137;
%"TAP"
"6","(-1750,4750)","2","mstr_standard","I54";
;
CDS_LIB"mstr_standard"
BODY_TYPE"PLUMBING"
HDL_TAP"TRUE";
"B \NAC \NWC"3;
"S \NAC"
BN"54"136;
%"TAP"
"6","(-1750,4650)","2","mstr_standard","I55";
;
CDS_LIB"mstr_standard"
BODY_TYPE"PLUMBING"
HDL_TAP"TRUE";
"B \NAC \NWC"3;
"S \NAC"
BN"52"133;
%"TAP"
"6","(-1750,4700)","2","mstr_standard","I56";
;
CDS_LIB"mstr_standard"
BODY_TYPE"PLUMBING"
HDL_TAP"TRUE";
"B \NAC \NWC"3;
"S \NAC"
BN"55"134;
%"TAP"
"6","(-1750,4600)","2","mstr_standard","I57";
;
CDS_LIB"mstr_standard"
BODY_TYPE"PLUMBING"
HDL_TAP"TRUE";
"B \NAC \NWC"3;
"S \NAC"
BN"53"132;
%"TAP"
"6","(-1750,4550)","2","mstr_standard","I58";
;
CDS_LIB"mstr_standard"
BODY_TYPE"PLUMBING"
HDL_TAP"TRUE";
"B \NAC \NWC"3;
"S \NAC"
BN"50"131;
%"TAP"
"6","(-1750,4500)","2","mstr_standard","I59";
;
CDS_LIB"mstr_standard"
BODY_TYPE"PLUMBING"
HDL_TAP"TRUE";
"B \NAC \NWC"3;
"S \NAC"
BN"51"130;
%"TAP"
"6","(900,4950)","2","mstr_standard","I6";
;
CDS_LIB"mstr_standard"
BODY_TYPE"PLUMBING"
HDL_TAP"TRUE";
"B \NAC \NWC"1;
"S \NAC"
BN"15"165;
%"TAP"
"6","(-1750,4450)","2","mstr_standard","I60";
;
CDS_LIB"mstr_standard"
BODY_TYPE"PLUMBING"
HDL_TAP"TRUE";
"B \NAC \NWC"3;
"S \NAC"
BN"48"129;
%"TAP"
"6","(-1750,4350)","2","mstr_standard","I61";
;
CDS_LIB"mstr_standard"
BODY_TYPE"PLUMBING"
HDL_TAP"TRUE";
"B \NAC \NWC"3;
"S \NAC"
BN"46"122;
%"TAP"
"6","(-1750,4400)","2","mstr_standard","I62";
;
CDS_LIB"mstr_standard"
BODY_TYPE"PLUMBING"
HDL_TAP"TRUE";
"B \NAC \NWC"3;
"S \NAC"
BN"49"128;
%"TAP"
"6","(-1750,4300)","2","mstr_standard","I63";
;
CDS_LIB"mstr_standard"
BODY_TYPE"PLUMBING"
HDL_TAP"TRUE";
"B \NAC \NWC"3;
"S \NAC"
BN"47"127;
%"TAP"
"6","(-1750,4250)","2","mstr_standard","I64";
;
CDS_LIB"mstr_standard"
BODY_TYPE"PLUMBING"
HDL_TAP"TRUE";
"B \NAC \NWC"3;
"S \NAC"
BN"44"126;
%"TAP"
"6","(-1750,4200)","2","mstr_standard","I65";
;
CDS_LIB"mstr_standard"
BODY_TYPE"PLUMBING"
HDL_TAP"TRUE";
"B \NAC \NWC"3;
"S \NAC"
BN"45"125;
%"SCONN288_H44441004"
"2","(-50,4350)","0","mstr_sconn","I66";
;
CDS_SEC"2"
LOCATION"J4B1"
PART_NUMBER"H44441-004"
MATERIAL"SCONN"
PACK_TYPE"PIP"
BOM_COST"MEM"
CDS_LIB"mstr_sconn"
SEC_TYPE"PIP"
SEC"2"
CDS_LOCATION"J4B1"
ROOM"DDR4_CH_D";
"DQS17P"
$PN"51"175;
"DQS9P"
$PN"7"156;
"DQS9N"
$PN"8"157;
"DQS8P"
$PN"197"158;
"DQS8N"
$PN"196"159;
"DQS7P"
$PN"278"160;
"DQS7N"
$PN"277"30;
"DQS6P"
$PN"267"161;
"DQS6N"
$PN"266"143;
"DQS5P"
$PN"256"144;
"DQS5N"
$PN"255"145;
"DQS4P"
$PN"245"146;
"DQS4N"
$PN"244"147;
"DQS3P"
$PN"186"148;
"DQS3N"
$PN"185"149;
"DQS2P"
$PN"175"150;
"DQS2N"
$PN"174"151;
"DQS1P"
$PN"164"152;
"DQS1N"
$PN"163"153;
"DQS17N"
$PN"52"176;
"DQS16P"
$PN"132"162;
"DQS16N"
$PN"133"163;
"DQS15P"
$PN"121"164;
"DQS15N"
$PN"122"165;
"DQS14P"
$PN"110"166;
"DQS14N"
$PN"111"167;
"DQS13P"
$PN"99"168;
"DQS13N"
$PN"100"169;
"DQS12P"
$PN"40"45;
"DQS12N"
$PN"41"170;
"DQS11P"
$PN"29"171;
"DQS11N"
$PN"30"172;
"DQS10P"
$PN"18"173;
"DQS10N"
$PN"19"174;
"DQS0P"
$PN"153"154;
"DQS0N"
$PN"152"155;
%"TAP"
"6","(-1750,4150)","2","mstr_standard","I67";
;
CDS_LIB"mstr_standard"
BODY_TYPE"PLUMBING"
HDL_TAP"TRUE";
"B \NAC \NWC"3;
"S \NAC"
BN"42"124;
%"TAP"
"6","(-1750,4100)","2","mstr_standard","I68";
;
CDS_LIB"mstr_standard"
BODY_TYPE"PLUMBING"
HDL_TAP"TRUE";
"B \NAC \NWC"3;
"S \NAC"
BN"43"123;
%"TAP"
"6","(-1750,4000)","2","mstr_standard","I69";
;
CDS_LIB"mstr_standard"
BODY_TYPE"PLUMBING"
HDL_TAP"TRUE";
"B \NAC \NWC"3;
"S \NAC"
BN"41"110;
%"TAP"
"6","(900,4750)","2","mstr_standard","I7";
;
CDS_LIB"mstr_standard"
BODY_TYPE"PLUMBING"
HDL_TAP"TRUE";
"B \NAC \NWC"1;
"S \NAC"
BN"13"169;
%"TAP"
"6","(-1750,3950)","2","mstr_standard","I70";
;
CDS_LIB"mstr_standard"
BODY_TYPE"PLUMBING"
HDL_TAP"TRUE";
"B \NAC \NWC"3;
"S \NAC"
BN"38"109;
%"TAP"
"6","(-1750,4050)","2","mstr_standard","I71";
;
CDS_LIB"mstr_standard"
BODY_TYPE"PLUMBING"
HDL_TAP"TRUE";
"B \NAC \NWC"3;
"S \NAC"
BN"40"111;
%"TAP"
"6","(-1750,3900)","2","mstr_standard","I72";
;
CDS_LIB"mstr_standard"
BODY_TYPE"PLUMBING"
HDL_TAP"TRUE";
"B \NAC \NWC"3;
"S \NAC"
BN"39"107;
%"TAP"
"6","(-1750,3850)","2","mstr_standard","I73";
;
CDS_LIB"mstr_standard"
BODY_TYPE"PLUMBING"
HDL_TAP"TRUE";
"B \NAC \NWC"3;
"S \NAC"
BN"36"108;
%"TAP"
"6","(-1750,3800)","2","mstr_standard","I74";
;
CDS_LIB"mstr_standard"
BODY_TYPE"PLUMBING"
HDL_TAP"TRUE";
"B \NAC \NWC"3;
"S \NAC"
BN"37"102;
%"TAP"
"6","(-1750,3700)","2","mstr_standard","I75";
;
CDS_LIB"mstr_standard"
BODY_TYPE"PLUMBING"
HDL_TAP"TRUE";
"B \NAC \NWC"3;
"S \NAC"
BN"35"106;
%"TAP"
"6","(-1750,3750)","2","mstr_standard","I76";
;
CDS_LIB"mstr_standard"
BODY_TYPE"PLUMBING"
HDL_TAP"TRUE";
"B \NAC \NWC"3;
"S \NAC"
BN"34"103;
%"TAP"
"6","(-1750,3650)","2","mstr_standard","I77";
;
CDS_LIB"mstr_standard"
BODY_TYPE"PLUMBING"
HDL_TAP"TRUE";
"B \NAC \NWC"3;
"S \NAC"
BN"32"105;
%"TAP"
"6","(-1750,3600)","2","mstr_standard","I78";
;
CDS_LIB"mstr_standard"
BODY_TYPE"PLUMBING"
HDL_TAP"TRUE";
"B \NAC \NWC"3;
"S \NAC"
BN"33"104;
%"TAP"
"6","(-1750,3450)","2","mstr_standard","I79";
;
CDS_LIB"mstr_standard"
BODY_TYPE"PLUMBING"
HDL_TAP"TRUE";
"B \NAC \NWC"3;
"S \NAC"
BN"28"101;
%"TAP"
"6","(900,4850)","2","mstr_standard","I8";
;
CDS_LIB"mstr_standard"
BODY_TYPE"PLUMBING"
HDL_TAP"TRUE";
"B \NAC \NWC"1;
"S \NAC"
BN"14"167;
%"TAP"
"6","(-1750,3550)","2","mstr_standard","I80";
;
CDS_LIB"mstr_standard"
BODY_TYPE"PLUMBING"
HDL_TAP"TRUE";
"B \NAC \NWC"3;
"S \NAC"
BN"30"99;
%"TAP"
"6","(-1750,3500)","2","mstr_standard","I81";
;
CDS_LIB"mstr_standard"
BODY_TYPE"PLUMBING"
HDL_TAP"TRUE";
"B \NAC \NWC"3;
"S \NAC"
BN"31"98;
%"TAP"
"6","(-1750,3350)","2","mstr_standard","I82";
;
CDS_LIB"mstr_standard"
BODY_TYPE"PLUMBING"
HDL_TAP"TRUE";
"B \NAC \NWC"3;
"S \NAC"
BN"26"97;
%"TAP"
"6","(-1750,3400)","2","mstr_standard","I83";
;
CDS_LIB"mstr_standard"
BODY_TYPE"PLUMBING"
HDL_TAP"TRUE";
"B \NAC \NWC"3;
"S \NAC"
BN"29"100;
%"TAP"
"6","(-1750,3300)","2","mstr_standard","I84";
;
CDS_LIB"mstr_standard"
BODY_TYPE"PLUMBING"
HDL_TAP"TRUE";
"B \NAC \NWC"3;
"S \NAC"
BN"27"92;
%"TAP"
"6","(-1750,3200)","2","mstr_standard","I85";
;
CDS_LIB"mstr_standard"
BODY_TYPE"PLUMBING"
HDL_TAP"TRUE";
"B \NAC \NWC"3;
"S \NAC"
BN"25"95;
%"TAP"
"6","(-1750,3250)","2","mstr_standard","I86";
;
CDS_LIB"mstr_standard"
BODY_TYPE"PLUMBING"
HDL_TAP"TRUE";
"B \NAC \NWC"3;
"S \NAC"
BN"24"96;
%"TAP"
"6","(-1750,3100)","2","mstr_standard","I87";
;
CDS_LIB"mstr_standard"
BODY_TYPE"PLUMBING"
HDL_TAP"TRUE";
"B \NAC \NWC"3;
"S \NAC"
BN"23"93;
%"TAP"
"6","(-1750,3150)","2","mstr_standard","I88";
;
CDS_LIB"mstr_standard"
BODY_TYPE"PLUMBING"
HDL_TAP"TRUE";
"B \NAC \NWC"3;
"S \NAC"
BN"22"94;
%"TAP"
"6","(-1750,3050)","2","mstr_standard","I89";
;
CDS_LIB"mstr_standard"
BODY_TYPE"PLUMBING"
HDL_TAP"TRUE";
"B \NAC \NWC"3;
"S \NAC"
BN"20"91;
%"TAP"
"6","(900,4650)","2","mstr_standard","I9";
;
CDS_LIB"mstr_standard"
BODY_TYPE"PLUMBING"
HDL_TAP"TRUE";
"B \NAC \NWC"1;
"S \NAC"
BN"12"170;
%"TAP"
"6","(-1750,3000)","2","mstr_standard","I90";
;
CDS_LIB"mstr_standard"
BODY_TYPE"PLUMBING"
HDL_TAP"TRUE";
"B \NAC \NWC"3;
"S \NAC"
BN"21"90;
%"TAP"
"6","(-1750,2950)","2","mstr_standard","I91";
;
CDS_LIB"mstr_standard"
BODY_TYPE"PLUMBING"
HDL_TAP"TRUE";
"B \NAC \NWC"3;
"S \NAC"
BN"18"89;
%"TAP"
"6","(-1750,2900)","2","mstr_standard","I92";
;
CDS_LIB"mstr_standard"
BODY_TYPE"PLUMBING"
HDL_TAP"TRUE";
"B \NAC \NWC"3;
"S \NAC"
BN"19"88;
%"TAP"
"6","(-1750,2800)","2","mstr_standard","I93";
;
CDS_LIB"mstr_standard"
BODY_TYPE"PLUMBING"
HDL_TAP"TRUE";
"B \NAC \NWC"3;
"S \NAC"
BN"17"86;
%"TAP"
"6","(-1750,2850)","2","mstr_standard","I94";
;
CDS_LIB"mstr_standard"
BODY_TYPE"PLUMBING"
HDL_TAP"TRUE";
"B \NAC \NWC"3;
"S \NAC"
BN"16"87;
%"TAP"
"6","(-1750,2750)","2","mstr_standard","I95";
;
CDS_LIB"mstr_standard"
BODY_TYPE"PLUMBING"
HDL_TAP"TRUE";
"B \NAC \NWC"3;
"S \NAC"
BN"14"82;
%"TAP"
"6","(-1750,2700)","2","mstr_standard","I96";
;
CDS_LIB"mstr_standard"
BODY_TYPE"PLUMBING"
HDL_TAP"TRUE";
"B \NAC \NWC"3;
"S \NAC"
BN"15"85;
%"TAP"
"6","(-1750,2600)","2","mstr_standard","I97";
;
CDS_LIB"mstr_standard"
BODY_TYPE"PLUMBING"
HDL_TAP"TRUE";
"B \NAC \NWC"3;
"S \NAC"
BN"13"83;
%"TAP"
"6","(-1750,2650)","2","mstr_standard","I98";
;
CDS_LIB"mstr_standard"
BODY_TYPE"PLUMBING"
HDL_TAP"TRUE";
"B \NAC \NWC"3;
"S \NAC"
BN"12"84;
%"TAP"
"6","(-1750,2550)","2","mstr_standard","I99";
;
CDS_LIB"mstr_standard"
BODY_TYPE"PLUMBING"
HDL_TAP"TRUE";
"B \NAC \NWC"3;
"S \NAC"
BN"10"81;
END.
